# T6G (Grand Teton) — schematic netlist excerpt (pin names and nets, part order shuffled) for the footprints in the layout excerpt that follows; sources: Cadence DE-HDL packaged netlist, KiCad conversion of 04192023_DAF0TMB3IC0_F0TG_MB_C_brd_V02_OCP.brd

J21  SCONN288_DDR506112002KQ  IO  pkg DDR288S_1-1VXC  page 90
  VIN_BULK0  = P12V_MEM_CPU0
  RFU0  = NC
  VIN_MGMT  = P3V3_AUX
  HSCL  = I3C_SPD_DDRE_CPU0_SCL
  HSDA  = I3C_SPD_DDRE_CPU0_SDA
  VSS0  = GND
  DQ0_A  = M_E_CPU0_SA_DQ<0>
  VSS1  = GND
  DQ1_A  = M_E_CPU0_SA_DQ<1>
  VSS2  = GND
  DQS0_A_T  = M_E_CPU0_SA_DQS_DP<0>
  DQS0_A_C  = M_E_CPU0_SA_DQS_DN<0>
  VSS3  = GND
  DQ4_A  = M_E_CPU0_SA_DQ<4>
  VSS4  = GND
  DQ5_A  = M_E_CPU0_SA_DQ<5>
  VSS5  = GND
  DQ8_A  = M_E_CPU0_SA_DQ<8>
  VSS6  = GND
  DQ9_A  = M_E_CPU0_SA_DQ<9>
  VSS7  = GND
  DQS1_A_T  = M_E_CPU0_SA_DQS_DP<1>
  DQS1_A_C  = M_E_CPU0_SA_DQS_DN<1>
  VSS8  = GND
  DQ12_A  = M_E_CPU0_SA_DQ<12>
  VSS9  = GND
  DQ13_A  = M_E_CPU0_SA_DQ<13>
  VSS10  = GND
  DQ16_A  = M_E_CPU0_SA_DQ<16>
  VSS11  = GND
  DQ17_A  = M_E_CPU0_SA_DQ<17>
  VSS12  = GND
  DQS2_A_T  = M_E_CPU0_SA_DQS_DP<2>
  DQS2_A_C  = M_E_CPU0_SA_DQS_DN<2>
  VSS13  = GND
  DQ20_A  = M_E_CPU0_SA_DQ<20>
  VSS14  = GND
  DQ21_A  = M_E_CPU0_SA_DQ<21>
  VSS15  = GND
  DQ24_A  = M_E_CPU0_SA_DQ<24>
  VSS16  = GND
  DQ25_A  = M_E_CPU0_SA_DQ<25>
  VSS17  = GND
  DQS3_A_T  = M_E_CPU0_SA_DQS_DP<3>
  DQS3_A_C  = M_E_CPU0_SA_DQS_DN<3>
  VSS18  = GND
  DQ28_A  = M_E_CPU0_SA_DQ<28>
  VSS19  = GND
  DQ29_A  = M_E_CPU0_SA_DQ<29>
  VSS20  = GND
  CB0_A  = M_E_CPU0_SA_CB<0>
  VSS21  = GND
  CB1_A  = M_E_CPU0_SA_CB<1>
  VSS22  = GND
  DQS4_A_T  = M_E_CPU0_SA_DQS_DP<4>
  DQS4_A_C  = M_E_CPU0_SA_DQS_DN<4>
  VSS23  = GND
  CB4_A  = M_E_CPU0_SA_CB<4>
  VSS24  = GND
  CB5_A  = M_E_CPU0_SA_CB<5>
  VSS25  = GND
  ALERT_N  = M_E_CPU0_ALERT_N
  VSS26  = GND
  CS0_A_N  = M_E_CPU0_SA_CS_N<0>
  VSS27  = GND
  CA0_A  = M_E_CPU0_SA_CA<0>
  VSS28  = GND
  CA2_A  = M_E_CPU0_SA_CA<2>
  VSS29  = GND
  CA4_A  = M_E_CPU0_SA_CA<4>
  VSS30  = GND
  CA6_A  = M_E_CPU0_SA_CA<6>
  VSS31  = GND
  PAR_A  = M_E_CPU0_SA_PAR
  VSS32  = GND
  CA0_B  = M_E_CPU0_SB_CA<0>
  VSS33  = GND
  CA2_B  = M_E_CPU0_SB_CA<2>
  VSS34  = GND
  CA4_B  = M_E_CPU0_SB_CA<4>
  VSS35  = GND
  CA6_B  = M_E_CPU0_SB_CA<6>
  VSS36  = GND
  CS0_B_N  = M_E_CPU0_SB_CS_N<0>
  VSS37  = GND
  \lbd||rsp_a_n\  = M_E_CPU0_SA_RSP<0>
  \lbs||rsp_b_n\  = M_E_CPU0_SB_RSP<0>
  VSS38  = GND
  CB4_B  = M_E_CPU0_SB_CB<4>
  VSS39  = GND
  CB5_B  = M_E_CPU0_SB_CB<5>
  VSS40  = GND
  \dqs9_b_t||tdqs9_b_t||dbi4_b_n\  = M_E_CPU0_SB_DQS_DP<9>
  \dqs9_b_c||tdqs9_b_c\  = M_E_CPU0_SB_DQS_DN<9>
  VSS41  = GND
  CB0_B  = M_E_CPU0_SB_CB<0>
  VSS42  = GND
  CB1_B  = M_E_CPU0_SB_CB<1>
  VSS43  = GND
  DQ0_B  = M_E_CPU0_SB_DQ<0>
  VSS44  = GND
  DQ1_B  = M_E_CPU0_SB_DQ<1>
  VSS45  = GND
  DQS0_B_T  = M_E_CPU0_SB_DQS_DP<0>
  DQS0_B_C  = M_E_CPU0_SB_DQS_DN<0>
  VSS46  = GND
  DQ4_B  = M_E_CPU0_SB_DQ<4>
  VSS47  = GND
  DQ5_B  = M_E_CPU0_SB_DQ<5>
  VSS48  = GND
  DQ8_B  = M_E_CPU0_SB_DQ<8>
  VSS49  = GND
  DQ9_B  = M_E_CPU0_SB_DQ<9>
  VSS50  = GND
  DQS1_B_T  = M_E_CPU0_SB_DQS_DP<1>
  DQS1_B_C  = M_E_CPU0_SB_DQS_DN<1>
  VSS51  = GND
  DQ12_B  = M_E_CPU0_SB_DQ<12>
  VSS52  = GND
  DQ13_B  = M_E_CPU0_SB_DQ<13>
  VSS53  = GND
  DQ16_B  = M_E_CPU0_SB_DQ<16>
  VSS54  = GND
  DQ17_B  = M_E_CPU0_SB_DQ<17>
  VSS55  = GND
  DQS2_B_T  = M_E_CPU0_SB_DQS_DP<2>
  DQS2_B_C  = M_E_CPU0_SB_DQS_DN<2>
  VSS56  = GND
  DQ20_B  = M_E_CPU0_SB_DQ<20>
  VSS57  = GND
  DQ21_B  = M_E_CPU0_SB_DQ<21>
  VSS58  = GND
  DQ24_B  = M_E_CPU0_SB_DQ<24>
  VSS59  = GND
  DQ25_B  = M_E_CPU0_SB_DQ<25>
  VSS60  = GND
  DQS3_B_T  = M_E_CPU0_SB_DQS_DP<3>
  DQS3_B_C  = M_E_CPU0_SB_DQS_DN<3>
  VSS61  = GND
  DQ28_B  = M_E_CPU0_SB_DQ<28>
  VSS62  = GND
  DQ29_B  = M_E_CPU0_SB_DQ<29>
  VSS63  = GND
  RFU1  = NC
  VIN_BULK1  = P12V_MEM_CPU0
  VIN_BULK2  = P12V_MEM_CPU0
  \pwr_good||fail_n\  = PWRGD_CHE_CPU0_DIMM
  HAS  = PD_CHE_CPU0_DIMM_SAA
  RFU2  = NC
  RFU3  = NC
  VSS64  = GND
  DQ2_A  = M_E_CPU0_SA_DQ<2>
  VSS65  = GND
  DQ3_A  = M_E_CPU0_SA_DQ<3>
  VSS66  = GND
  \dqs5_a_c||tdqs5_a_c||dqs5_a_t||tdqs5_a_t\  = M_E_CPU0_SA_DQS_DN<5>
  \dqs5_a_t||tdqs5_a_t\  = M_E_CPU0_SA_DQS_DP<5>
  VSS67  = GND
  DQ6_A  = M_E_CPU0_SA_DQ<6>
  VSS68  = GND
  DQ7_A  = M_E_CPU0_SA_DQ<7>
  VSS69  = GND
  DQ10_A  = M_E_CPU0_SA_DQ<10>
  VSS70  = GND
  DQ11_A  = M_E_CPU0_SA_DQ<11>
  VSS71  = GND
  \dqs6_a_c||tdqs6_a_c||dqs6_a_t||tdqs6_a_t\  = M_E_CPU0_SA_DQS_DN<6>
  \dqs6_a_t||tdqs6_a_t\  = M_E_CPU0_SA_DQS_DP<6>
  VSS72  = GND
  DQ14_A  = M_E_CPU0_SA_DQ<14>
  VSS73  = GND
  DQ15_A  = M_E_CPU0_SA_DQ<15>
  VSS74  = GND
  DQ18_A  = M_E_CPU0_SA_DQ<18>
  VSS75  = GND
  DQ19_A  = M_E_CPU0_SA_DQ<19>
  VSS76  = GND
  \dqs7_a_c||tdqs7_a_c\  = M_E_CPU0_SA_DQS_DN<7>
  \dqs7_a_t||tdqs7_a_t\  = M_E_CPU0_SA_DQS_DP<7>
  VSS77  = GND
  DQ22_A  = M_E_CPU0_SA_DQ<22>
  VSS78  = GND
  DQ23_A  = M_E_CPU0_SA_DQ<23>
  VSS79  = GND
  DQ26_A  = M_E_CPU0_SA_DQ<26>
  VSS80  = GND
  DQ27_A  = M_E_CPU0_SA_DQ<27>
  VSS81  = GND
  \dqs8_a_c||tdqs8_a_c\  = M_E_CPU0_SA_DQS_DN<8>
  \dqs8_a_t||tdqs8_a_t\  = M_E_CPU0_SA_DQS_DP<8>
  VSS82  = GND
  DQ30_A  = M_E_CPU0_SA_DQ<30>
  VSS83  = GND
  DQ31_A  = M_E_CPU0_SA_DQ<31>
  VSS84  = GND
  CB2_A  = M_E_CPU0_SA_CB<2>
  VSS85  = GND
  CB3_A  = M_E_CPU0_SA_CB<3>
  VSS86  = GND
  \dqs9_a_c||tdqs9_a_c\  = M_E_CPU0_SA_DQS_DN<9>
  \dqs9_a_t||tdqs9_a_t\  = M_E_CPU0_SA_DQS_DP<9>
  VSS87  = GND
  CB6_A  = M_E_CPU0_SA_CB<6>
  VSS88  = GND
  CB7_A  = M_E_CPU0_SA_CB<7>
  VSS89  = GND
  RESET_N  = M_E_CPU0_RESET_N
  VSS90  = GND
  CS1_A_N  = M_E_CPU0_SA_CS_N<1>
  VSS91  = GND
  CA1_A  = M_E_CPU0_SA_CA<1>
  VSS92  = GND
  CA3_A  = M_E_CPU0_SA_CA<3>
  VSS93  = GND
  CA5_A  = M_E_CPU0_SA_CA<5>
  VSS94  = GND
  CK_T  = M_E_CPU0_CLK_DP<0>
  CK_C  = M_E_CPU0_CLK_DN<0>
  VSS95  = GND
  RFU4  = NC
  CA1_B  = M_E_CPU0_SB_CA<1>
  VSS96  = GND
  CA3_B  = M_E_CPU0_SB_CA<3>
  VSS97  = GND
  CA5_B  = M_E_CPU0_SB_CA<5>
  VSS98  = GND
  PAR_B  = M_E_CPU0_SB_PAR
  VSS99  = GND
  CS1_B_N  = M_E_CPU0_SB_CS_N<1>
  VSS100  = GND
  RFU5  = NC
  RFU6  = NC
  VSS101  = GND
  CB6_B  = M_E_CPU0_SB_CB<6>
  VSS102  = GND
  CB7_B  = M_E_CPU0_SB_CB<7>
  VSS103  = GND
  DQS4_B_C  = M_E_CPU0_SB_DQS_DN<4>
  DQS4_B_T  = M_E_CPU0_SB_DQS_DP<4>
  VSS104  = GND
  CB2_B  = M_E_CPU0_SB_CB<2>
  VSS105  = GND
  CB3_B  = M_E_CPU0_SB_CB<3>
  VSS106  = GND
  DQ2_B  = M_E_CPU0_SB_DQ<2>
  VSS107  = GND
  DQ3_B  = M_E_CPU0_SB_DQ<3>
  VSS108  = GND
  \dqs5_b_c||tdqs5_b_c\  = M_E_CPU0_SB_DQS_DN<5>
  \dqs5_b_t||tdqs5_b_t\  = M_E_CPU0_SB_DQS_DP<5>
  VSS109  = GND
  DQ6_B  = M_E_CPU0_SB_DQ<6>
  VSS110  = GND
  DQ7_B  = M_E_CPU0_SB_DQ<7>
  VSS111  = GND
  DQ10_B  = M_E_CPU0_SB_DQ<10>
  VSS112  = GND
  DQ11_B  = M_E_CPU0_SB_DQ<11>
  VSS113  = GND
  \dqs6_b_c||tdqs6_b_c\  = M_E_CPU0_SB_DQS_DN<6>
  \dqs6_b_t||tdqs6_b_t\  = M_E_CPU0_SB_DQS_DP<6>
  VSS114  = GND
  DQ14_B  = M_E_CPU0_SB_DQ<14>
  VSS115  = GND
  DQ15_B  = M_E_CPU0_SB_DQ<15>
  VSS116  = GND
  DQ18_B  = M_E_CPU0_SB_DQ<18>
  VSS117  = GND
  DQ19_B  = M_E_CPU0_SB_DQ<19>
  VSS118  = GND
  \dqs7_b_c||tdqs7_b_c\  = M_E_CPU0_SB_DQS_DN<7>
  \dqs7_b_t||tdqs7_b_t\  = M_E_CPU0_SB_DQS_DP<7>
  VSS119  = GND
  DQ22_B  = M_E_CPU0_SB_DQ<22>
  VSS120  = GND
  DQ23_B  = M_E_CPU0_SB_DQ<23>
  VSS121  = GND
  DQ26_B  = M_E_CPU0_SB_DQ<26>
  VSS122  = GND
  DQ27_B  = M_E_CPU0_SB_DQ<27>
  VSS123  = GND
  \dqs8_b_c||tdqs8_b_c\  = M_E_CPU0_SB_DQS_DN<8>
  \dqs8_b_t||tdqs8_b_t\  = M_E_CPU0_SB_DQS_DP<8>
  VSS124  = GND
  DQ30_B  = M_E_CPU0_SB_DQ<30>
  VSS125  = GND
  DQ31_B  = M_E_CPU0_SB_DQ<31>
  VSS126  = GND
  G1  = GND
  G2  = GND
  G3  = GND

(kicad_pcb
	(version 20260206)
	(generator "pcbnew")
	(generator_version "10.0")
	(general
		(thickness 1.6)
		(legacy_teardrops no)
	)
	(paper "A4")
	(title_block
		(title "04192023_DAF0TMB3IC0_F0TG_MB_C_brd_V02_OCP.brd")
		(comment 1 "Grand Teton / footprint 3 of 8354 (J21), pads 139-184 of 291")
	)
	(layers
		(0 "F.Cu" signal "TOP")
		(4 "In1.Cu" signal "GND")
		(6 "In2.Cu" signal "IN1")
		(8 "In3.Cu" signal "GND1")
		(10 "In4.Cu" signal "IN2")
		(12 "In5.Cu" signal "GND2")
		(14 "In6.Cu" signal "IN3")
		(16 "In7.Cu" signal "GND3")
		(18 "In8.Cu" signal "VCC")
		(20 "In9.Cu" signal "VCC1")
		(22 "In10.Cu" signal "GND4")
		(24 "In11.Cu" signal "IN4")
		(26 "In12.Cu" signal "GND5")
		(28 "In13.Cu" signal "IN5")
		(30 "In14.Cu" signal "GND6")
		(32 "In15.Cu" signal "IN6")
		(34 "In16.Cu" signal "GND7")
		(2 "B.Cu" signal "BOTTOM")
		(9 "F.Adhes" user "F.Adhesive")
		(11 "B.Adhes" user "B.Adhesive")
		(13 "F.Paste" user "Package Geometry/Pastemask Top")
		(15 "B.Paste" user "Package Geometry/Pastemask Bottom")
		(5 "F.SilkS" user "Ref Des/Silkscreen Top")
		(7 "B.SilkS" user "Ref Des/Silkscreen Bottom")
		(1 "F.Mask" user "Board Geometry/Soldermask Top")
		(3 "B.Mask" user "Board Geometry/Soldermask Bottom")
		(17 "Dwgs.User" user "User.Drawings")
		(19 "Cmts.User" user "User.Comments")
		(21 "Eco1.User" user "User.Eco1")
		(23 "Eco2.User" user "User.Eco2")
		(25 "Edge.Cuts" user "Board Geometry/Outline")
		(27 "Margin" user)
		(31 "F.CrtYd" user "Package Geometry/Place Bound Top")
		(29 "B.CrtYd" user "Package Geometry/Place Bound Bottom")
		(35 "F.Fab" user "Ref Des/Assembly Top")
		(33 "B.Fab" user "Ref Des/Assembly Bottom")
	)
	(footprint ""
		(layer "F.Cu")
		(at 275.142198 -255.560068 180)
		(property "Reference" "J21"
			(at -2.2098 -81.984088 0)
			(unlocked yes)
			(layer "F.SilkS")
			(effects
				(font
					(size 0.7874 0.5842)
					(thickness 0.1524)
				)
			)
		)
		(property "Value" ""
			(at 0 0 180)
			(layer "F.Fab")
			(effects
				(font
					(size 1.27 1.27)
				)
			)
		)
		(duplicate_pad_numbers_are_jumpers no)
		(pad "139" smd rect
			(at -2.050034 59.075066 90)
			(size 0.519938 1.4986)
			(layers "F.Cu" "F.Mask" "F.Paste")
			(net "GND")
		)
		(pad "140" smd rect
			(at -2.050034 59.92495 90)
			(size 0.519938 1.4986)
			(layers "F.Cu" "F.Mask" "F.Paste")
			(net "M_E_CPU0_SB_DQ<28>")
		)
		(pad "141" smd rect
			(at -2.050034 60.775088 90)
			(size 0.519938 1.4986)
			(layers "F.Cu" "F.Mask" "F.Paste")
			(net "GND")
		)
		(pad "142" smd rect
			(at -2.050034 61.624972 90)
			(size 0.519938 1.4986)
			(layers "F.Cu" "F.Mask" "F.Paste")
			(net "M_E_CPU0_SB_DQ<29>")
		)
		(pad "143" smd rect
			(at -2.050034 62.47511 90)
			(size 0.519938 1.4986)
			(layers "F.Cu" "F.Mask" "F.Paste")
			(net "GND")
		)
		(pad "144" smd rect
			(at -2.050034 63.324994 90)
			(size 0.519938 1.4986)
			(layers "F.Cu" "F.Mask" "F.Paste")
			(net "Net_2306")
		)
		(pad "145" smd rect
			(at 2.050034 -63.324994 90)
			(size 0.519938 1.4986)
			(layers "F.Cu" "F.Mask" "F.Paste")
			(net "P12V_MEM_CPU0")
		)
		(pad "146" smd rect
			(at 2.050034 -62.47511 90)
			(size 0.519938 1.4986)
			(layers "F.Cu" "F.Mask" "F.Paste")
			(net "P12V_MEM_CPU0")
		)
		(pad "147" smd rect
			(at 2.050034 -61.624972 90)
			(size 0.519938 1.4986)
			(layers "F.Cu" "F.Mask" "F.Paste")
			(net "PWRGD_CHE_CPU0_DIMM")
		)
		(pad "148" smd rect
			(at 2.050034 -60.775088 90)
			(size 0.519938 1.4986)
			(layers "F.Cu" "F.Mask" "F.Paste")
			(net "PD_CHE_CPU0_DIMM_SAA")
		)
		(pad "149" smd rect
			(at 2.050034 -59.92495 90)
			(size 0.519938 1.4986)
			(layers "F.Cu" "F.Mask" "F.Paste")
			(net "Net_2307")
		)
		(pad "150" smd rect
			(at 2.050034 -59.075066 90)
			(size 0.519938 1.4986)
			(layers "F.Cu" "F.Mask" "F.Paste")
			(net "Net_2308")
		)
		(pad "151" smd rect
			(at 2.050034 -58.224928 90)
			(size 0.519938 1.4986)
			(layers "F.Cu" "F.Mask" "F.Paste")
			(net "GND")
		)
		(pad "152" smd rect
			(at 2.050034 -57.375044 90)
			(size 0.519938 1.4986)
			(layers "F.Cu" "F.Mask" "F.Paste")
			(net "M_E_CPU0_SA_DQ<2>")
		)
		(pad "153" smd rect
			(at 2.050034 -56.524906 90)
			(size 0.519938 1.4986)
			(layers "F.Cu" "F.Mask" "F.Paste")
			(net "GND")
		)
		(pad "154" smd rect
			(at 2.050034 -55.675022 90)
			(size 0.519938 1.4986)
			(layers "F.Cu" "F.Mask" "F.Paste")
			(net "M_E_CPU0_SA_DQ<3>")
		)
		(pad "155" smd rect
			(at 2.050034 -54.824884 90)
			(size 0.519938 1.4986)
			(layers "F.Cu" "F.Mask" "F.Paste")
			(net "GND")
		)
		(pad "156" smd rect
			(at 2.050034 -53.975 90)
			(size 0.519938 1.4986)
			(layers "F.Cu" "F.Mask" "F.Paste")
			(net "M_E_CPU0_SA_DQS_DN<5>")
		)
		(pad "157" smd rect
			(at 2.050034 -53.125116 90)
			(size 0.519938 1.4986)
			(layers "F.Cu" "F.Mask" "F.Paste")
			(net "M_E_CPU0_SA_DQS_DP<5>")
		)
		(pad "158" smd rect
			(at 2.050034 -52.274978 90)
			(size 0.519938 1.4986)
			(layers "F.Cu" "F.Mask" "F.Paste")
			(net "GND")
		)
		(pad "159" smd rect
			(at 2.050034 -51.425094 90)
			(size 0.519938 1.4986)
			(layers "F.Cu" "F.Mask" "F.Paste")
			(net "M_E_CPU0_SA_DQ<6>")
		)
		(pad "160" smd rect
			(at 2.050034 -50.574956 90)
			(size 0.519938 1.4986)
			(layers "F.Cu" "F.Mask" "F.Paste")
			(net "GND")
		)
		(pad "161" smd rect
			(at 2.050034 -49.725072 90)
			(size 0.519938 1.4986)
			(layers "F.Cu" "F.Mask" "F.Paste")
			(net "M_E_CPU0_SA_DQ<7>")
		)
		(pad "162" smd rect
			(at 2.050034 -48.874934 90)
			(size 0.519938 1.4986)
			(layers "F.Cu" "F.Mask" "F.Paste")
			(net "GND")
		)
		(pad "163" smd rect
			(at 2.050034 -48.02505 90)
			(size 0.519938 1.4986)
			(layers "F.Cu" "F.Mask" "F.Paste")
			(net "M_E_CPU0_SA_DQ<10>")
		)
		(pad "164" smd rect
			(at 2.050034 -47.174912 90)
			(size 0.519938 1.4986)
			(layers "F.Cu" "F.Mask" "F.Paste")
			(net "GND")
		)
		(pad "165" smd rect
			(at 2.050034 -46.325028 90)
			(size 0.519938 1.4986)
			(layers "F.Cu" "F.Mask" "F.Paste")
			(net "M_E_CPU0_SA_DQ<11>")
		)
		(pad "166" smd rect
			(at 2.050034 -45.47489 90)
			(size 0.519938 1.4986)
			(layers "F.Cu" "F.Mask" "F.Paste")
			(net "GND")
		)
		(pad "167" smd rect
			(at 2.050034 -44.625006 90)
			(size 0.519938 1.4986)
			(layers "F.Cu" "F.Mask" "F.Paste")
			(net "M_E_CPU0_SA_DQS_DN<6>")
		)
		(pad "168" smd rect
			(at 2.050034 -43.775122 90)
			(size 0.519938 1.4986)
			(layers "F.Cu" "F.Mask" "F.Paste")
			(net "M_E_CPU0_SA_DQS_DP<6>")
		)
		(pad "169" smd rect
			(at 2.050034 -42.924984 90)
			(size 0.519938 1.4986)
			(layers "F.Cu" "F.Mask" "F.Paste")
			(net "GND")
		)
		(pad "170" smd rect
			(at 2.050034 -42.0751 90)
			(size 0.519938 1.4986)
			(layers "F.Cu" "F.Mask" "F.Paste")
			(net "M_E_CPU0_SA_DQ<14>")
		)
		(pad "171" smd rect
			(at 2.050034 -41.224962 90)
			(size 0.519938 1.4986)
			(layers "F.Cu" "F.Mask" "F.Paste")
			(net "GND")
		)
		(pad "172" smd rect
			(at 2.050034 -40.375078 90)
			(size 0.519938 1.4986)
			(layers "F.Cu" "F.Mask" "F.Paste")
			(net "M_E_CPU0_SA_DQ<15>")
		)
		(pad "173" smd rect
			(at 2.050034 -39.52494 90)
			(size 0.519938 1.4986)
			(layers "F.Cu" "F.Mask" "F.Paste")
			(net "GND")
		)
		(pad "174" smd rect
			(at 2.050034 -38.675056 90)
			(size 0.519938 1.4986)
			(layers "F.Cu" "F.Mask" "F.Paste")
			(net "M_E_CPU0_SA_DQ<18>")
		)
		(pad "175" smd rect
			(at 2.050034 -37.824918 90)
			(size 0.519938 1.4986)
			(layers "F.Cu" "F.Mask" "F.Paste")
			(net "GND")
		)
		(pad "176" smd rect
			(at 2.050034 -36.975034 90)
			(size 0.519938 1.4986)
			(layers "F.Cu" "F.Mask" "F.Paste")
			(net "M_E_CPU0_SA_DQ<19>")
		)
		(pad "177" smd rect
			(at 2.050034 -36.124896 90)
			(size 0.519938 1.4986)
			(layers "F.Cu" "F.Mask" "F.Paste")
			(net "GND")
		)
		(pad "178" smd rect
			(at 2.050034 -35.275012 90)
			(size 0.519938 1.4986)
			(layers "F.Cu" "F.Mask" "F.Paste")
			(net "M_E_CPU0_SA_DQS_DN<7>")
		)
		(pad "179" smd rect
			(at 2.050034 -34.425128 90)
			(size 0.519938 1.4986)
			(layers "F.Cu" "F.Mask" "F.Paste")
			(net "M_E_CPU0_SA_DQS_DP<7>")
		)
		(pad "180" smd rect
			(at 2.050034 -33.57499 90)
			(size 0.519938 1.4986)
			(layers "F.Cu" "F.Mask" "F.Paste")
			(net "GND")
		)
		(pad "181" smd rect
			(at 2.050034 -32.725106 90)
			(size 0.519938 1.4986)
			(layers "F.Cu" "F.Mask" "F.Paste")
			(net "M_E_CPU0_SA_DQ<22>")
		)
		(pad "182" smd rect
			(at 2.050034 -31.874968 90)
			(size 0.519938 1.4986)
			(layers "F.Cu" "F.Mask" "F.Paste")
			(net "GND")
		)
		(pad "183" smd rect
			(at 2.050034 -31.025084 90)
			(size 0.519938 1.4986)
			(layers "F.Cu" "F.Mask" "F.Paste")
			(net "M_E_CPU0_SA_DQ<23>")
		)
		(pad "184" smd rect
			(at 2.050034 -30.174946 90)
			(size 0.519938 1.4986)
			(layers "F.Cu" "F.Mask" "F.Paste")
			(net "GND")
		)
	)
)
